#ISCELL
  logical_power bom_note *
  *
#ISCELL
  logical_power cad_note *
  *
#ISCELL
  mstr_misc dns *
  *
#ISCELL
  pure_quanta quanta_title_block_c *
  *
#ISCELL
  standard offpage *
  page232_i1
#ISCELL
  logical_power universal_gnd *
  page232_i10
#CELL
  pure_quanta 74lvc1g07se7 *
  page232_i11
#ISCELL
  logical_power universal_power *
  page232_i12
#CELL
  pure_quanta q_res *
  page232_i13
#CELL
  pure_quanta mosfet_nch_gds_esd_protected *
  page232_i14
#ISCELL
  logical_power universal_gnd *
  page232_i15
#CELL
  pure_quanta q_res *
  page232_i16
#ISCELL
  logical_power universal_gnd *
  page232_i17
#CELL
  pure_quanta q_res *
  page232_i18
#ISCELL
  logical_power universal_power *
  page232_i19
#ISCELL
  logical_power universal_gnd *
  page232_i2
#CELL
  pure_quanta q_res *
  page232_i20
#CELL
  pure_quanta q_res *
  page232_i21
#CELL
  pure_quanta q_res *
  page232_i22
#ISCELL
  logical_power universal_gnd *
  page232_i23
#CELL
  pure_quanta q_cap *
  page232_i24
#ISCELL
  standard offpage *
  page232_i25
#CELL
  pure_quanta tps3895adryr *
  page232_i26
#CELL
  pure_quanta adm1086akszreel7 *
  page232_i27
#ISCELL
  logical_power universal_power *
  page232_i28
#ISCELL
  logical_power universal_power *
  page232_i29
#CELL
  pure_quanta q_res *
  page232_i3
#ISCELL
  logical_power universal_gnd *
  page232_i30
#CELL
  pure_quanta q_res *
  page232_i31
#CELL
  pure_quanta q_res *
  page232_i32
#CELL
  pure_quanta q_res *
  page232_i33
#ISCELL
  logical_power universal_gnd *
  page232_i34
#CELL
  pure_quanta q_cap *
  page232_i35
#CELL
  pure_quanta q_res *
  page232_i36
#ISCELL
  logical_power universal_power *
  page232_i37
#ISCELL
  logical_power universal_gnd *
  page232_i38
#CELL
  pure_quanta mosfet_nch_gds_esd_protected *
  page232_i39
#CELL
  pure_quanta q_res *
  page232_i4
#CELL
  pure_quanta q_res *
  page232_i40
#ISCELL
  logical_power universal_power *
  page232_i41
#ISCELL
  standard offpage *
  page232_i42
#ISCELL
  standard offpage *
  page232_i43
#ISCELL
  standard offpage *
  page232_i44
#ISCELL
  logical_power universal_gnd *
  page232_i45
#ISCELL
  logical_power universal_gnd *
  page232_i46
#CELL
  pure_quanta q_cap *
  page232_i47
#ISCELL
  standard offpage *
  page232_i48
#ISCELL
  logical_power universal_power *
  page232_i5
#ISCELL
  logical_power universal_gnd *
  page232_i6
#CELL
  pure_quanta q_cap *
  page232_i7
#ISCELL
  logical_power universal_gnd *
  page232_i8
#CELL
  pure_quanta q_cap *
  page232_i9
